(kicad_pcb
	(version 20241229)
	(generator "pcbnew")
	(generator_version "9.0")
	(general
		(thickness 1.6296)
		(legacy_teardrops no)
	)
	(paper "A3")
	(title_block
		(title "Thunderbolt to 10GbE adapter")
		(date "2026-04-21")
		(rev "1.1.0")
		(company "Antmicro Ltd")
		(comment 1 "www.antmicro.com")
		(comment 9 "footprint 290 of 703 (U3), pads 1-74 of 96")
	)
	(layers
		(0 "F.Cu" signal)
		(4 "In1.Cu" signal)
		(6 "In2.Cu" signal)
		(8 "In3.Cu" signal)
		(10 "In4.Cu" signal)
		(12 "In5.Cu" signal)
		(14 "In6.Cu" signal)
		(2 "B.Cu" signal)
		(9 "F.Adhes" user "F.Adhesive")
		(11 "B.Adhes" user "B.Adhesive")
		(13 "F.Paste" user)
		(15 "B.Paste" user)
		(5 "F.SilkS" user "F.Silkscreen")
		(7 "B.SilkS" user "B.Silkscreen")
		(1 "F.Mask" user)
		(3 "B.Mask" user)
		(17 "Dwgs.User" user "User.Drawings")
		(19 "Cmts.User" user "User.Comments")
		(21 "Eco1.User" user "User.Eco1")
		(23 "Eco2.User" user "User.Eco2")
		(25 "Edge.Cuts" user)
		(27 "Margin" user)
		(31 "F.CrtYd" user "F.Courtyard")
		(29 "B.CrtYd" user "B.Courtyard")
		(35 "F.Fab" user)
		(33 "B.Fab" user)
	)
	(footprint "antmicro-footprints:IC_TPS65983BAZBHR"
		(layer "F.Cu")
		(at 135 136.5 -90)
		(property "Reference" "U3"
			(at -3.7 2.8 0)
			(unlocked yes)
			(layer "F.SilkS")
			(effects
				(font
					(size 0.7 0.7)
					(thickness 0.15)
				)
			)
		)
		(property "Value" "TPS65983BAZBHR"
			(at 0 4.1 270)
			(unlocked yes)
			(layer "F.Fab")
			(effects
				(font
					(size 0.7 0.7)
					(thickness 0.15)
				)
			)
		)
		(property "Datasheet" "https://www.ti.com/lit/ds/symlink/tps65983b.pdf?ts=1678712702533&ref_url=https%253A%252F%252Fwww.ti.com%252Fproduct%252FTPS65983B"
			(at 0 0 270)
			(layer "F.Fab")
			(hide yes)
			(effects
				(font
					(size 1.27 1.27)
					(thickness 0.15)
				)
			)
		)
		(property "Description" "USB Interface IC Universal USB Type-C and Power Delivery (PD) 3.0 controller 96-NFBGA -10°C to 85"
			(at 0 0 270)
			(layer "F.Fab")
			(hide yes)
			(effects
				(font
					(size 1.27 1.27)
					(thickness 0.15)
				)
			)
		)
		(property "MPN" "TPS65983BAZBHR"
			(at 0 0 270)
			(unlocked yes)
			(layer "F.Fab")
			(hide yes)
			(effects
				(font
					(size 1 1)
					(thickness 0.15)
				)
			)
		)
		(property "Manufacturer" "Texas Instruments"
			(at 0 0 270)
			(unlocked yes)
			(layer "F.Fab")
			(hide yes)
			(effects
				(font
					(size 1 1)
					(thickness 0.15)
				)
			)
		)
		(property "License" "Apache-2.0"
			(at 0 0 270)
			(unlocked yes)
			(layer "F.Fab")
			(hide yes)
			(effects
				(font
					(size 1 1)
					(thickness 0.15)
				)
			)
		)
		(property "Author" "Antmicro"
			(at 0 0 270)
			(unlocked yes)
			(layer "F.Fab")
			(hide yes)
			(effects
				(font
					(size 1 1)
					(thickness 0.15)
				)
			)
		)
		(sheetname "/PD and TB DC-DC/")
		(sheetfile "PD_and_TB_DC_DC.kicad_sch")
		(attr smd)
		(pad "A1" smd circle
			(at -2.5 -2.5 180)
			(size 0.25 0.25)
			(layers "F.Cu" "F.Mask")
			(net 23 "GND")
			(pinfunction "GND")
			(pintype "power_in")
			(solder_paste_margin_ratio 0)
		)
		(pad "A2" smd oval
			(at -2 -2.5 270)
			(size 0.17 0.25)
			(layers "F.Cu" "F.Mask" "F.Paste")
			(net 175 "Net-(U3-LDO_1V8D)")
			(pinfunction "LDO_1V8D")
			(pintype "power_out")
			(solder_paste_margin_ratio 0)
		)
		(pad "A3" smd oval
			(at -1.5 -2.5 270)
			(size 0.17 0.25)
			(layers "F.Cu" "F.Mask" "F.Paste")
			(net 397 "/PD and TB DC-DC/TB_FLASH.CLK")
			(pinfunction "SPI_CLK")
			(pintype "output")
			(solder_paste_margin_ratio 0)
		)
		(pad "A4" smd oval
			(at -1 -2.5 270)
			(size 0.17 0.25)
			(layers "F.Cu" "F.Mask" "F.Paste")
			(net 357 "/PD and TB DC-DC/TB_FLASH.MISO")
			(pinfunction "SPI_POCI")
			(pintype "input")
			(solder_paste_margin_ratio 0)
		)
		(pad "A5" smd oval
			(at -0.5 -2.5 270)
			(size 0.17 0.25)
			(layers "F.Cu" "F.Mask" "F.Paste")
			(net 198 "Net-(U3-I2C_SDA2)")
			(pinfunction "I2C_SDA2")
			(pintype "bidirectional")
			(solder_paste_margin_ratio 0)
		)
		(pad "A6" smd oval
			(at 0 -2.5 270)
			(size 0.17 0.25)
			(layers "F.Cu" "F.Mask" "F.Paste")
			(net 170 "PP_HV")
			(pinfunction "PP_HV")
			(pintype "power_in")
			(solder_paste_margin_ratio 0)
		)
		(pad "A7" smd oval
			(at 0.5 -2.5 270)
			(size 0.17 0.25)
			(layers "F.Cu" "F.Mask" "F.Paste")
			(net 170 "PP_HV")
			(pinfunction "PP_HV")
			(pintype "power_in")
			(solder_paste_margin_ratio 0)
		)
		(pad "A8" smd oval
			(at 1 -2.5 270)
			(size 0.17 0.25)
			(layers "F.Cu" "F.Mask" "F.Paste")
			(net 170 "PP_HV")
			(pinfunction "PP_HV")
			(pintype "power_in")
			(solder_paste_margin_ratio 0)
		)
		(pad "A9" smd oval
			(at 1.5 -2.5 270)
			(size 0.17 0.25)
			(layers "F.Cu" "F.Mask" "F.Paste")
			(net 290 "unconnected-(U3-HV_GATE2-PadA9)")
			(pinfunction "HV_GATE2")
			(pintype "output+no_connect")
			(solder_paste_margin_ratio 0)
		)
		(pad "A10" smd oval
			(at 2 -2.5 270)
			(size 0.17 0.25)
			(layers "F.Cu" "F.Mask" "F.Paste")
			(net 291 "unconnected-(U3-SENSEN-PadA10)")
			(pinfunction "SENSEN")
			(pintype "input+no_connect")
			(solder_paste_margin_ratio 0)
		)
		(pad "A11" smd circle
			(at 2.5 -2.5 180)
			(size 0.25 0.25)
			(layers "F.Cu" "F.Mask")
			(net 173 "PP_5V0")
			(pinfunction "PP_5V0")
			(pintype "power_in")
			(solder_paste_margin_ratio 0)
		)
		(pad "B1" smd oval
			(at -2.5 -2 270)
			(size 0.25 0.17)
			(layers "F.Cu" "F.Mask" "F.Paste")
			(net 57 "+3V3_TB")
			(pinfunction "VDDIO")
			(pintype "power_in")
			(solder_paste_margin_ratio 0)
		)
		(pad "B2" smd circle
			(at -2 -2 180)
			(size 0.25 0.25)
			(layers "F.Cu" "F.Mask")
			(net 201 "Net-(U3-GPIO0(HD3_AMSEL))")
			(pinfunction "GPIO0(HD3_AMSEL)")
			(pintype "bidirectional")
			(solder_paste_margin_ratio 0)
		)
		(pad "B3" smd circle
			(at -1.5 -2 180)
			(size 0.25 0.25)
			(layers "F.Cu" "F.Mask")
			(net 359 "/PD and TB DC-DC/TB_FLASH.~{CE}")
			(pinfunction "SPI_CSZ")
			(pintype "output")
			(solder_paste_margin_ratio 0)
		)
		(pad "B4" smd circle
			(at -1 -2 180)
			(size 0.25 0.25)
			(layers "F.Cu" "F.Mask")
			(net 398 "/PD and TB DC-DC/TB_FLASH.MOSI")
			(pinfunction "SPI_PICO")
			(pintype "output")
			(solder_paste_margin_ratio 0)
		)
		(pad "B5" smd circle
			(at -0.5 -2 180)
			(size 0.25 0.25)
			(layers "F.Cu" "F.Mask")
			(net 199 "Net-(U3-I2C_SCL2)")
			(pinfunction "I2C_SCL2")
			(pintype "bidirectional")
			(solder_paste_margin_ratio 0)
		)
		(pad "B6" smd circle
			(at 0 -2 180)
			(size 0.25 0.25)
			(layers "F.Cu" "F.Mask")
			(net 200 "Net-(U3-I2C_IRQ2Z)")
			(pinfunction "I2C_IRQ2Z")
			(pintype "output")
			(solder_paste_margin_ratio 0)
		)
		(pad "B7" smd circle
			(at 0.5 -2 180)
			(size 0.25 0.25)
			(layers "F.Cu" "F.Mask")
			(net 170 "PP_HV")
			(pinfunction "PP_HV")
			(pintype "power_in")
			(solder_paste_margin_ratio 0)
		)
		(pad "B8" smd circle
			(at 1 -2 180)
			(size 0.25 0.25)
			(layers "F.Cu" "F.Mask")
			(net 23 "GND")
			(pinfunction "GND")
			(pintype "power_in")
			(solder_paste_margin_ratio 0)
		)
		(pad "B9" smd circle
			(at 1.5 -2 180)
			(size 0.25 0.25)
			(layers "F.Cu" "F.Mask")
			(net 292 "unconnected-(U3-HV_GATE1-PadB9)")
			(pinfunction "HV_GATE1")
			(pintype "output+no_connect")
			(solder_paste_margin_ratio 0)
		)
		(pad "B10" smd circle
			(at 2 -2 180)
			(size 0.25 0.25)
			(layers "F.Cu" "F.Mask")
			(net 293 "unconnected-(U3-SENSEP-PadB10)")
			(pinfunction "SENSEP")
			(pintype "input+no_connect")
			(solder_paste_margin_ratio 0)
		)
		(pad "B11" smd oval
			(at 2.5 -2 270)
			(size 0.25 0.17)
			(layers "F.Cu" "F.Mask" "F.Paste")
			(net 173 "PP_5V0")
			(pinfunction "PP_5V0")
			(pintype "power_in")
			(solder_paste_margin_ratio 0)
		)
		(pad "C1" smd oval
			(at -2.5 -1.5 270)
			(size 0.25 0.17)
			(layers "F.Cu" "F.Mask" "F.Paste")
			(net 372 "/PD and TB DC-DC/I2C1.IRQ")
			(pinfunction "I2C_IRQ1Z")
			(pintype "output")
			(solder_paste_margin_ratio 0)
		)
		(pad "C2" smd circle
			(at -2 -1.5 180)
			(size 0.25 0.25)
			(layers "F.Cu" "F.Mask")
			(net 294 "unconnected-(U3-GPIO1(CONFIG0)-PadC2)")
			(pinfunction "GPIO1(CONFIG0)")
			(pintype "bidirectional+no_connect")
			(solder_paste_margin_ratio 0)
		)
		(pad "C10" smd circle
			(at 2 -1.5 180)
			(size 0.25 0.25)
			(layers "F.Cu" "F.Mask")
			(net 202 "Net-(U3-GPIO4(HPD_TXRX))")
			(pinfunction "GPIO4(HPD_TXRX)")
			(pintype "bidirectional")
			(solder_paste_margin_ratio 0)
		)
		(pad "C11" smd oval
			(at 2.5 -1.5 270)
			(size 0.25 0.17)
			(layers "F.Cu" "F.Mask" "F.Paste")
			(net 173 "PP_5V0")
			(pinfunction "PP_5V0")
			(pintype "power_in")
			(solder_paste_margin_ratio 0)
		)
		(pad "D1" smd oval
			(at -2.5 -1 270)
			(size 0.25 0.17)
			(layers "F.Cu" "F.Mask" "F.Paste")
			(net 375 "/PD and TB DC-DC/I2C1.SDA")
			(pinfunction "I2C_SDA1")
			(pintype "bidirectional")
			(solder_paste_margin_ratio 0)
		)
		(pad "D2" smd circle
			(at -2 -1 180)
			(size 0.25 0.25)
			(layers "F.Cu" "F.Mask")
			(net 373 "/PD and TB DC-DC/I2C1.SCL")
			(pinfunction "I2C_SCL1")
			(pintype "bidirectional")
			(solder_paste_margin_ratio 0)
		)
		(pad "D5" smd circle
			(at -0.5 -1 180)
			(size 0.25 0.25)
			(layers "F.Cu" "F.Mask")
			(net 206 "Net-(U3-DEBUG_CTL2(GPIO17,_I2CADDR_B5))")
			(pinfunction "DEBUG_CTL2(GPIO17,_I2CADDR_B5)")
			(pintype "bidirectional")
			(solder_paste_margin_ratio 0)
		)
		(pad "D6" smd circle
			(at 0 -1 180)
			(size 0.25 0.25)
			(layers "F.Cu" "F.Mask")
			(net 210 "Net-(U3-HRESET)")
			(pinfunction "HRESET")
			(pintype "input")
			(solder_paste_margin_ratio 0)
		)
		(pad "D7" smd circle
			(at 0.5 -1 180)
			(size 0.25 0.25)
			(layers "F.Cu" "F.Mask")
			(net 204 "Net-(U3-GPIO7)")
			(pinfunction "GPIO7")
			(pintype "bidirectional")
			(solder_paste_margin_ratio 0)
		)
		(pad "D8" smd circle
			(at 1 -1 180)
			(size 0.25 0.25)
			(layers "F.Cu" "F.Mask")
			(net 23 "GND")
			(pinfunction "GND")
			(pintype "power_in")
			(solder_paste_margin_ratio 0)
		)
		(pad "D10" smd circle
			(at 2 -1 180)
			(size 0.25 0.25)
			(layers "F.Cu" "F.Mask")
			(net 295 "unconnected-(U3-GPIO2-PadD10)")
			(pinfunction "GPIO2")
			(pintype "bidirectional+no_connect")
			(solder_paste_margin_ratio 0)
		)
		(pad "D11" smd oval
			(at 2.5 -1 270)
			(size 0.25 0.17)
			(layers "F.Cu" "F.Mask" "F.Paste")
			(net 173 "PP_5V0")
			(pinfunction "PP_5V0")
			(pintype "power_in")
			(solder_paste_margin_ratio 0)
		)
		(pad "E1" smd oval
			(at -2.5 -0.5 270)
			(size 0.25 0.17)
			(layers "F.Cu" "F.Mask" "F.Paste")
			(net 176 "Net-(U3-LDO_BMC)")
			(pinfunction "LDO_BMC")
			(pintype "power_out")
			(solder_paste_margin_ratio 0)
		)
		(pad "E2" smd circle
			(at -2 -0.5 180)
			(size 0.25 0.25)
			(layers "F.Cu" "F.Mask")
			(net 205 "Net-(U3-UART_RX)")
			(pinfunction "UART_TX")
			(pintype "output")
			(solder_paste_margin_ratio 0)
		)
		(pad "E4" smd circle
			(at -1 -0.5 180)
			(size 0.25 0.25)
			(layers "F.Cu" "F.Mask")
			(net 207 "Net-(U3-DEBUG_CTL1(GPIO16,_I2CADDR_B4))")
			(pinfunction "DEBUG_CTL1(GPIO16,_I2CADDR_B4)")
			(pintype "bidirectional")
			(solder_paste_margin_ratio 0)
		)
		(pad "E5" smd circle
			(at -0.5 -0.5 180)
			(size 0.25 0.25)
			(layers "F.Cu" "F.Mask")
			(net 23 "GND")
			(pinfunction "GND")
			(pintype "power_in")
			(solder_paste_margin_ratio 0)
		)
		(pad "E6" smd circle
			(at 0 -0.5 180)
			(size 0.25 0.25)
			(layers "F.Cu" "F.Mask")
			(net 23 "GND")
			(pinfunction "GND")
			(pintype "power_in")
			(solder_paste_margin_ratio 0)
		)
		(pad "E7" smd circle
			(at 0.5 -0.5 180)
			(size 0.25 0.25)
			(layers "F.Cu" "F.Mask")
			(net 23 "GND")
			(pinfunction "GND")
			(pintype "power_in")
			(solder_paste_margin_ratio 0)
		)
		(pad "E8" smd circle
			(at 1 -0.5 180)
			(size 0.25 0.25)
			(layers "F.Cu" "F.Mask")
			(net 23 "GND")
			(pinfunction "GND")
			(pintype "power_in")
			(solder_paste_margin_ratio 0)
		)
		(pad "E10" smd circle
			(at 2 -0.5 180)
			(size 0.25 0.25)
			(layers "F.Cu" "F.Mask")
			(net 296 "unconnected-(U3-GPIO5(HPD_RX)-PadE10)")
			(pinfunction "GPIO5(HPD_RX)")
			(pintype "bidirectional+no_connect")
			(solder_paste_margin_ratio 0)
		)
		(pad "E11" smd oval
			(at 2.5 -0.5 270)
			(size 0.25 0.17)
			(layers "F.Cu" "F.Mask" "F.Paste")
			(net 209 "Net-(U3-MRESET(GPIO11))")
			(pinfunction "MRESET(GPIO11)")
			(pintype "bidirectional")
			(solder_paste_margin_ratio 0)
		)
		(pad "F1" smd oval
			(at -2.5 0 270)
			(size 0.25 0.17)
			(layers "F.Cu" "F.Mask" "F.Paste")
			(net 208 "Net-(U3-I2C_ADDR)")
			(pinfunction "I2C_ADDR")
			(pintype "bidirectional")
			(solder_paste_margin_ratio 0)
		)
		(pad "F2" smd circle
			(at -2 0 180)
			(size 0.25 0.25)
			(layers "F.Cu" "F.Mask")
			(net 205 "Net-(U3-UART_RX)")
			(pinfunction "UART_RX")
			(pintype "input")
			(solder_paste_margin_ratio 0)
		)
		(pad "F4" smd circle
			(at -1 0 180)
			(size 0.25 0.25)
			(layers "F.Cu" "F.Mask")
			(net 297 "unconnected-(U3-SWD_DATA-PadF4)")
			(pinfunction "SWD_DATA")
			(pintype "bidirectional+no_connect")
			(solder_paste_margin_ratio 0)
		)
		(pad "F5" smd circle
			(at -0.5 0 180)
			(size 0.25 0.25)
			(layers "F.Cu" "F.Mask")
			(net 23 "GND")
			(pinfunction "GND")
			(pintype "power_in")
			(solder_paste_margin_ratio 0)
		)
		(pad "F6" smd circle
			(at 0 0 180)
			(size 0.25 0.25)
			(layers "F.Cu" "F.Mask")
			(net 23 "GND")
			(pinfunction "GND")
			(pintype "power_in")
			(solder_paste_margin_ratio 0)
		)
		(pad "F7" smd circle
			(at 0.5 0 180)
			(size 0.25 0.25)
			(layers "F.Cu" "F.Mask")
			(net 23 "GND")
			(pinfunction "GND")
			(pintype "power_in")
			(solder_paste_margin_ratio 0)
		)
		(pad "F8" smd circle
			(at 1 0 180)
			(size 0.25 0.25)
			(layers "F.Cu" "F.Mask")
			(net 23 "GND")
			(pinfunction "GND")
			(pintype "power_in")
			(solder_paste_margin_ratio 0)
		)
		(pad "F10" smd circle
			(at 2 0 180)
			(size 0.25 0.25)
			(layers "F.Cu" "F.Mask")
			(net 211 "Net-(U3-BUSPOWERZ(GPIO10))")
			(pinfunction "BUSPOWERZ(GPIO10)")
			(pintype "bidirectional")
			(solder_paste_margin_ratio 0)
		)
		(pad "F11" smd oval
			(at 2.5 0 270)
			(size 0.25 0.17)
			(layers "F.Cu" "F.Mask" "F.Paste")
			(net 377 "/PD and TB DC-DC/RESET_N")
			(pinfunction "RESETZ(GPIO9)")
			(pintype "bidirectional")
			(solder_paste_margin_ratio 0)
		)
		(pad "G1" smd oval
			(at -2.5 0.5 270)
			(size 0.25 0.17)
			(layers "F.Cu" "F.Mask" "F.Paste")
			(net 304 "/PD and TB DC-DC/TPS_3V3")
			(pinfunction "LDO_3V3")
			(pintype "power_out")
			(solder_paste_margin_ratio 0)
		)
		(pad "G2" smd circle
			(at -2 0.5 180)
			(size 0.25 0.25)
			(layers "F.Cu" "F.Mask")
			(net 212 "Net-(U3-R_OSC)")
			(pinfunction "R_OSC")
			(pintype "bidirectional")
			(solder_paste_margin_ratio 0)
		)
		(pad "G4" smd circle
			(at -1 0.5 180)
			(size 0.25 0.25)
			(layers "F.Cu" "F.Mask")
			(net 298 "unconnected-(U3-SWD_CLK-PadG4)")
			(pinfunction "SWD_CLK")
			(pintype "input+no_connect")
			(solder_paste_margin_ratio 0)
		)
		(pad "G5" smd circle
			(at -0.5 0.5 180)
			(size 0.25 0.25)
			(layers "F.Cu" "F.Mask")
			(net 23 "GND")
			(pinfunction "GND")
			(pintype "power_in")
			(solder_paste_margin_ratio 0)
		)
		(pad "G6" smd circle
			(at 0 0.5 180)
			(size 0.25 0.25)
			(layers "F.Cu" "F.Mask")
			(net 23 "GND")
			(pinfunction "GND")
			(pintype "power_in")
			(solder_paste_margin_ratio 0)
		)
		(pad "G7" smd circle
			(at 0.5 0.5 180)
			(size 0.25 0.25)
			(layers "F.Cu" "F.Mask")
			(net 23 "GND")
			(pinfunction "GND")
			(pintype "power_in")
			(solder_paste_margin_ratio 0)
		)
		(pad "G8" smd circle
			(at 1 0.5 180)
			(size 0.25 0.25)
			(layers "F.Cu" "F.Mask")
			(net 23 "GND")
			(pinfunction "GND")
			(pintype "power_in")
			(solder_paste_margin_ratio 0)
		)
		(pad "G10" smd circle
			(at 2 0.5 180)
			(size 0.25 0.25)
			(layers "F.Cu" "F.Mask")
			(net 203 "Net-(U3-GPIO6)")
			(pinfunction "GPIO6")
			(pintype "bidirectional")
			(solder_paste_margin_ratio 0)
		)
		(pad "G11" smd oval
			(at 2.5 0.5 270)
			(size 0.25 0.17)
			(layers "F.Cu" "F.Mask" "F.Paste")
			(net 299 "unconnected-(U3-GPIO3(HD3_EN)-PadG11)")
			(pinfunction "GPIO3(HD3_EN)")
			(pintype "bidirectional+no_connect")
			(solder_paste_margin_ratio 0)
		)
		(pad "H1" smd oval
			(at -2.5 1 270)
			(size 0.25 0.17)
			(layers "F.Cu" "F.Mask" "F.Paste")
			(net 57 "+3V3_TB")
			(pinfunction "VIN_3V3")
			(pintype "power_in")
			(solder_paste_margin_ratio 0)
		)
		(pad "H2" smd circle
			(at -2 1 180)
			(size 0.25 0.25)
			(layers "F.Cu" "F.Mask")
			(net 171 "Net-(U3-VOUT_3V3)")
			(pinfunction "VOUT_3V3")
			(pintype "power_out")
			(solder_paste_margin_ratio 0)
		)
		(pad "H4" smd circle
			(at -1 1 180)
			(size 0.25 0.25)
			(layers "F.Cu" "F.Mask")
			(net 23 "GND")
			(pinfunction "GND")
			(pintype "power_in")
			(solder_paste_margin_ratio 0)
		)
		(pad "H5" smd circle
			(at -0.5 1 180)
			(size 0.25 0.25)
			(layers "F.Cu" "F.Mask")
			(net 23 "GND")
			(pinfunction "GND")
			(pintype "power_in")
			(solder_paste_margin_ratio 0)
		)
		(pad "H6" smd circle
			(at 0 1 180)
			(size 0.25 0.25)
			(layers "F.Cu" "F.Mask")
			(net 300 "unconnected-(U3-GPIO8-PadH6)")
			(pinfunction "GPIO8")
			(pintype "bidirectional+no_connect")
			(solder_paste_margin_ratio 0)
		)
		(pad "H7" smd circle
			(at 0.5 1 180)
			(size 0.25 0.25)
			(layers "F.Cu" "F.Mask")
			(net 165 "Net-(U3-SS)")
			(pinfunction "SS")
			(pintype "output")
			(solder_paste_margin_ratio 0)
		)
		(pad "H8" smd circle
			(at 1 1 180)
			(size 0.25 0.25)
			(layers "F.Cu" "F.Mask")
			(net 23 "GND")
			(pinfunction "GND")
			(pintype "power_in")
			(solder_paste_margin_ratio 0)
		)
		(pad "H10" smd circle
			(at 2 1 180)
			(size 0.25 0.25)
			(layers "F.Cu" "F.Mask")
			(net 173 "PP_5V0")
			(pinfunction "PP_CABLE")
			(pintype "power_in")
			(solder_paste_margin_ratio 0)
		)
		(pad "H11" smd oval
			(at 2.5 1 270)
			(size 0.25 0.17)
			(layers "F.Cu" "F.Mask" "F.Paste")
			(net 182 "VBUS")
			(pinfunction "VBUS")
			(pintype "power_in")
			(solder_paste_margin_ratio 0)
		)
		(pad "J1" smd oval
			(at -2.5 1.5 270)
			(size 0.25 0.17)
			(layers "F.Cu" "F.Mask" "F.Paste")
			(net 69 "/PD and TB DC-DC/AUX.+")
			(pinfunction "AUX_P")
			(pintype "bidirectional")
			(solder_paste_margin_ratio 0)
		)
		(pad "J2" smd circle
			(at -2 1.5 180)
			(size 0.25 0.25)
			(layers "F.Cu" "F.Mask")
			(net 79 "/PD and TB DC-DC/AUX.-")
			(pinfunction "AUX_N")
			(pintype "bidirectional")
			(solder_paste_margin_ratio 0)
		)
		(pad "J10" smd circle
			(at 2 1.5 180)
			(size 0.25 0.25)
			(layers "F.Cu" "F.Mask")
			(net 182 "VBUS")
			(pinfunction "VBUS")
			(pintype "power_in")
			(solder_paste_margin_ratio 0)
		)
		(pad "J11" smd oval
			(at 2.5 1.5 270)
			(size 0.25 0.17)
			(layers "F.Cu" "F.Mask" "F.Paste")
			(net 182 "VBUS")
			(pinfunction "VBUS")
			(pintype "power_in")
			(solder_paste_margin_ratio 0)
		)
	)
)
